(kicad_pcb
	(version 20260206)
	(generator "pcbnew")
	(generator_version "10.0")
	(general
		(thickness 1.6)
		(legacy_teardrops no)
	)
	(paper "A4")
	(title_block
		(title "03242023_DA0F0TMBIJ0_F0T_Motherboard_J_brd_V01_OCP.brd")
		(comment 1 "Grand Teton / footprints 683-689 of 6105")
	)
	(layers
		(0 "F.Cu" signal "TOP")
		(4 "In1.Cu" signal "GND")
		(6 "In2.Cu" signal "IN1")
		(8 "In3.Cu" signal "GND1")
		(10 "In4.Cu" signal "IN2")
		(12 "In5.Cu" signal "GND2")
		(14 "In6.Cu" signal "IN3")
		(16 "In7.Cu" signal "GND3")
		(18 "In8.Cu" signal "VCC")
		(20 "In9.Cu" signal "VCC1")
		(22 "In10.Cu" signal "GND4")
		(24 "In11.Cu" signal "IN4")
		(26 "In12.Cu" signal "GND5")
		(28 "In13.Cu" signal "IN5")
		(30 "In14.Cu" signal "GND6")
		(32 "In15.Cu" signal "IN6")
		(34 "In16.Cu" signal "GND7")
		(2 "B.Cu" signal "BOTTOM")
		(9 "F.Adhes" user "F.Adhesive")
		(11 "B.Adhes" user "B.Adhesive")
		(13 "F.Paste" user "Package Geometry/Pastemask Top")
		(15 "B.Paste" user "Package Geometry/Pastemask Bottom")
		(5 "F.SilkS" user "Ref Des/Silkscreen Top")
		(7 "B.SilkS" user "Ref Des/Silkscreen Bottom")
		(1 "F.Mask" user "Board Geometry/Soldermask Top")
		(3 "B.Mask" user "Board Geometry/Soldermask Bottom")
		(17 "Dwgs.User" user "User.Drawings")
		(19 "Cmts.User" user "User.Comments")
		(21 "Eco1.User" user "User.Eco1")
		(23 "Eco2.User" user "User.Eco2")
		(25 "Edge.Cuts" user "Board Geometry/Outline")
		(27 "Margin" user)
		(31 "F.CrtYd" user "Package Geometry/Place Bound Top")
		(29 "B.CrtYd" user "Package Geometry/Place Bound Bottom")
		(35 "F.Fab" user "Ref Des/Assembly Top")
		(33 "B.Fab" user "Ref Des/Assembly Bottom")
	)
	(footprint ""
		(layer "F.Cu")
		(at 399.312384 -17.612614 90)
		(property "Reference" "C845"
			(at 0 0 90)
			(layer "F.SilkS")
			(hide yes)
			(effects
				(font
					(size 1.27 1.27)
				)
			)
		)
		(property "Value" ""
			(at 0 0 90)
			(layer "F.Fab")
			(effects
				(font
					(size 1.27 1.27)
				)
			)
		)
		(duplicate_pad_numbers_are_jumpers no)
		(fp_line
			(start 0.299974 -0.150114)
			(end 0.299974 0.150114)
			(stroke
				(width 0.1)
				(type default)
			)
			(layer "F.Fab")
		)
		(fp_line
			(start -0.299974 -0.150114)
			(end 0.299974 -0.150114)
			(stroke
				(width 0.1)
				(type default)
			)
			(layer "F.Fab")
		)
		(fp_line
			(start 0.299974 0.150114)
			(end -0.299974 0.150114)
			(stroke
				(width 0.1)
				(type default)
			)
			(layer "F.Fab")
		)
		(fp_line
			(start -0.299974 0.150114)
			(end -0.299974 -0.150114)
			(stroke
				(width 0.1)
				(type default)
			)
			(layer "F.Fab")
		)
		(pad "1" smd rect
			(at -0.2667 0 90)
			(size 0.3048 0.381)
			(layers "F.Cu" "F.Mask" "F.Paste")
			(net "P5E_CPU0_PE1_TX_C_DP<12>")
		)
		(pad "2" smd rect
			(at 0.2667 0 90)
			(size 0.3048 0.381)
			(layers "F.Cu" "F.Mask" "F.Paste")
			(net "P5E_CPU0_PE1_TX_DP<12>")
		)
	)
	(footprint ""
		(layer "F.Cu")
		(at 430.991518 -366.65027)
		(property "Reference" "PC722_P0_3"
			(at 0 0 0)
			(layer "F.SilkS")
			(hide yes)
			(effects
				(font
					(size 1.27 1.27)
				)
			)
		)
		(property "Value" ""
			(at 0 0 0)
			(layer "F.Fab")
			(effects
				(font
					(size 1.27 1.27)
				)
			)
		)
		(duplicate_pad_numbers_are_jumpers no)
		(fp_line
			(start -1.524 -0.762)
			(end 1.524 -0.762)
			(stroke
				(width 0.1524)
				(type default)
			)
			(layer "F.SilkS")
		)
		(fp_line
			(start -1.524 0.762)
			(end -1.524 -0.762)
			(stroke
				(width 0.1524)
				(type default)
			)
			(layer "F.SilkS")
		)
		(fp_line
			(start 1.524 -0.762)
			(end 1.524 0.762)
			(stroke
				(width 0.1524)
				(type default)
			)
			(layer "F.SilkS")
		)
		(fp_line
			(start 1.524 0.762)
			(end -1.524 0.762)
			(stroke
				(width 0.1524)
				(type default)
			)
			(layer "F.SilkS")
		)
		(fp_line
			(start -1.1049 -0.724916)
			(end -1.1049 0.724916)
			(stroke
				(width 0.1)
				(type default)
			)
			(layer "F.Fab")
		)
		(fp_line
			(start -1.1049 0.724916)
			(end 1.1049 0.724916)
			(stroke
				(width 0.1)
				(type default)
			)
			(layer "F.Fab")
		)
		(fp_line
			(start 1.1049 -0.724916)
			(end -1.1049 -0.724916)
			(stroke
				(width 0.1)
				(type default)
			)
			(layer "F.Fab")
		)
		(fp_line
			(start 1.1049 0.724916)
			(end 1.1049 -0.724916)
			(stroke
				(width 0.1)
				(type default)
			)
			(layer "F.Fab")
		)
		(pad "1" smd rect
			(at -0.889 0 180)
			(size 1.016 1.27)
			(layers "F.Cu" "F.Mask" "F.Paste")
			(net "SW_P12V_PVCCFA_EHV_FIVRA_CPU0_R")
		)
		(pad "2" smd rect
			(at 0.889 0 180)
			(size 1.016 1.27)
			(layers "F.Cu" "F.Mask" "F.Paste")
			(net "GND")
		)
	)
	(footprint ""
		(layer "F.Cu")
		(at 162.23488 -58.511948)
		(property "Reference" "R2476"
			(at 0 0 0)
			(layer "F.SilkS")
			(hide yes)
			(effects
				(font
					(size 1.27 1.27)
				)
			)
		)
		(property "Value" ""
			(at 0 0 0)
			(layer "F.Fab")
			(effects
				(font
					(size 1.27 1.27)
				)
			)
		)
		(duplicate_pad_numbers_are_jumpers no)
		(fp_line
			(start -0.7874 -0.4064)
			(end 0.7874 -0.4064)
			(stroke
				(width 0.1524)
				(type default)
			)
			(layer "F.SilkS")
		)
		(fp_line
			(start -0.7874 0.4064)
			(end -0.7874 -0.4064)
			(stroke
				(width 0.1524)
				(type default)
			)
			(layer "F.SilkS")
		)
		(fp_line
			(start 0.7874 -0.4064)
			(end 0.7874 0.4064)
			(stroke
				(width 0.1524)
				(type default)
			)
			(layer "F.SilkS")
		)
		(fp_line
			(start 0.7874 0.4064)
			(end -0.7874 0.4064)
			(stroke
				(width 0.1524)
				(type default)
			)
			(layer "F.SilkS")
		)
		(fp_line
			(start -0.67945 -0.305054)
			(end -0.12065 -0.305054)
			(stroke
				(width 0.1)
				(type default)
			)
			(layer "F.Fab")
		)
		(fp_line
			(start -0.67945 0.3048)
			(end -0.67945 -0.305054)
			(stroke
				(width 0.1)
				(type default)
			)
			(layer "F.Fab")
		)
		(fp_line
			(start -0.12065 -0.305054)
			(end -0.12065 -0.2794)
			(stroke
				(width 0.1)
				(type default)
			)
			(layer "F.Fab")
		)
		(fp_line
			(start -0.12065 -0.2794)
			(end 0.12065 -0.2794)
			(stroke
				(width 0.1)
				(type default)
			)
			(layer "F.Fab")
		)
		(fp_line
			(start -0.12065 0.2794)
			(end -0.12065 0.3048)
			(stroke
				(width 0.1)
				(type default)
			)
			(layer "F.Fab")
		)
		(fp_line
			(start -0.12065 0.3048)
			(end -0.67945 0.3048)
			(stroke
				(width 0.1)
				(type default)
			)
			(layer "F.Fab")
		)
		(fp_line
			(start 0.120396 0.2794)
			(end -0.12065 0.2794)
			(stroke
				(width 0.1)
				(type default)
			)
			(layer "F.Fab")
		)
		(fp_line
			(start 0.120396 0.3048)
			(end 0.120396 0.2794)
			(stroke
				(width 0.1)
				(type default)
			)
			(layer "F.Fab")
		)
		(fp_line
			(start 0.12065 -0.3048)
			(end 0.67945 -0.3048)
			(stroke
				(width 0.1)
				(type default)
			)
			(layer "F.Fab")
		)
		(fp_line
			(start 0.12065 -0.2794)
			(end 0.12065 -0.3048)
			(stroke
				(width 0.1)
				(type default)
			)
			(layer "F.Fab")
		)
		(fp_line
			(start 0.67945 -0.3048)
			(end 0.67945 0.3048)
			(stroke
				(width 0.1)
				(type default)
			)
			(layer "F.Fab")
		)
		(fp_line
			(start 0.67945 0.3048)
			(end 0.120396 0.3048)
			(stroke
				(width 0.1)
				(type default)
			)
			(layer "F.Fab")
		)
		(pad "1" smd circle
			(at -0.40005 0)
			(size 0 0)
			(layers "F.Cu" "F.Mask" "F.Paste")
			(net "SMB_PCIE_M2_0_EN")
		)
		(pad "2" smd circle
			(at 0.40005 0)
			(size 0 0)
			(layers "F.Cu" "F.Mask" "F.Paste")
			(net "PWRGD_P1V8_PCH_AUX")
		)
	)
	(footprint ""
		(layer "F.Cu")
		(at 140.70838 -33.466024)
		(property "Reference" "C1879"
			(at 0 0 0)
			(layer "F.SilkS")
			(hide yes)
			(effects
				(font
					(size 1.27 1.27)
				)
			)
		)
		(property "Value" ""
			(at 0 0 0)
			(layer "F.Fab")
			(effects
				(font
					(size 1.27 1.27)
				)
			)
		)
		(duplicate_pad_numbers_are_jumpers no)
		(fp_line
			(start -0.7874 -0.4064)
			(end 0.7874 -0.4064)
			(stroke
				(width 0.1524)
				(type default)
			)
			(layer "F.SilkS")
		)
		(fp_line
			(start -0.7874 0.4064)
			(end -0.7874 -0.4064)
			(stroke
				(width 0.1524)
				(type default)
			)
			(layer "F.SilkS")
		)
		(fp_line
			(start 0.7874 -0.4064)
			(end 0.7874 0.4064)
			(stroke
				(width 0.1524)
				(type default)
			)
			(layer "F.SilkS")
		)
		(fp_line
			(start 0.7874 0.4064)
			(end -0.7874 0.4064)
			(stroke
				(width 0.1524)
				(type default)
			)
			(layer "F.SilkS")
		)
		(fp_line
			(start -0.67945 -0.305054)
			(end -0.12065 -0.305054)
			(stroke
				(width 0.1)
				(type default)
			)
			(layer "F.Fab")
		)
		(fp_line
			(start -0.67945 0.3048)
			(end -0.67945 -0.305054)
			(stroke
				(width 0.1)
				(type default)
			)
			(layer "F.Fab")
		)
		(fp_line
			(start -0.12065 -0.305054)
			(end -0.12065 -0.2794)
			(stroke
				(width 0.1)
				(type default)
			)
			(layer "F.Fab")
		)
		(fp_line
			(start -0.12065 -0.2794)
			(end 0.12065 -0.2794)
			(stroke
				(width 0.1)
				(type default)
			)
			(layer "F.Fab")
		)
		(fp_line
			(start -0.12065 0.2794)
			(end -0.12065 0.3048)
			(stroke
				(width 0.1)
				(type default)
			)
			(layer "F.Fab")
		)
		(fp_line
			(start -0.12065 0.3048)
			(end -0.67945 0.3048)
			(stroke
				(width 0.1)
				(type default)
			)
			(layer "F.Fab")
		)
		(fp_line
			(start 0.120396 0.2794)
			(end -0.12065 0.2794)
			(stroke
				(width 0.1)
				(type default)
			)
			(layer "F.Fab")
		)
		(fp_line
			(start 0.120396 0.3048)
			(end 0.120396 0.2794)
			(stroke
				(width 0.1)
				(type default)
			)
			(layer "F.Fab")
		)
		(fp_line
			(start 0.12065 -0.3048)
			(end 0.67945 -0.3048)
			(stroke
				(width 0.1)
				(type default)
			)
			(layer "F.Fab")
		)
		(fp_line
			(start 0.12065 -0.2794)
			(end 0.12065 -0.3048)
			(stroke
				(width 0.1)
				(type default)
			)
			(layer "F.Fab")
		)
		(fp_line
			(start 0.67945 -0.3048)
			(end 0.67945 0.3048)
			(stroke
				(width 0.1)
				(type default)
			)
			(layer "F.Fab")
		)
		(fp_line
			(start 0.67945 0.3048)
			(end 0.120396 0.3048)
			(stroke
				(width 0.1)
				(type default)
			)
			(layer "F.Fab")
		)
		(pad "1" smd circle
			(at -0.40005 0)
			(size 0 0)
			(layers "F.Cu" "F.Mask" "F.Paste")
			(net "P3V3_AUX")
		)
		(pad "2" smd circle
			(at 0.40005 0)
			(size 0 0)
			(layers "F.Cu" "F.Mask" "F.Paste")
			(net "GND")
		)
	)
	(footprint ""
		(layer "F.Cu")
		(at 385.716272 -59.719464)
		(property "Reference" "R768"
			(at 0 0 0)
			(layer "F.SilkS")
			(hide yes)
			(effects
				(font
					(size 1.27 1.27)
				)
			)
		)
		(property "Value" ""
			(at 0 0 0)
			(layer "F.Fab")
			(effects
				(font
					(size 1.27 1.27)
				)
			)
		)
		(duplicate_pad_numbers_are_jumpers no)
		(fp_line
			(start -0.7874 -0.4064)
			(end 0.7874 -0.4064)
			(stroke
				(width 0.1524)
				(type default)
			)
			(layer "F.SilkS")
		)
		(fp_line
			(start -0.7874 0.4064)
			(end -0.7874 -0.4064)
			(stroke
				(width 0.1524)
				(type default)
			)
			(layer "F.SilkS")
		)
		(fp_line
			(start 0.7874 -0.4064)
			(end 0.7874 0.4064)
			(stroke
				(width 0.1524)
				(type default)
			)
			(layer "F.SilkS")
		)
		(fp_line
			(start 0.7874 0.4064)
			(end -0.7874 0.4064)
			(stroke
				(width 0.1524)
				(type default)
			)
			(layer "F.SilkS")
		)
		(fp_line
			(start -0.67945 -0.305054)
			(end -0.12065 -0.305054)
			(stroke
				(width 0.1)
				(type default)
			)
			(layer "F.Fab")
		)
		(fp_line
			(start -0.67945 0.3048)
			(end -0.67945 -0.305054)
			(stroke
				(width 0.1)
				(type default)
			)
			(layer "F.Fab")
		)
		(fp_line
			(start -0.12065 -0.305054)
			(end -0.12065 -0.2794)
			(stroke
				(width 0.1)
				(type default)
			)
			(layer "F.Fab")
		)
		(fp_line
			(start -0.12065 -0.2794)
			(end 0.12065 -0.2794)
			(stroke
				(width 0.1)
				(type default)
			)
			(layer "F.Fab")
		)
		(fp_line
			(start -0.12065 0.2794)
			(end -0.12065 0.3048)
			(stroke
				(width 0.1)
				(type default)
			)
			(layer "F.Fab")
		)
		(fp_line
			(start -0.12065 0.3048)
			(end -0.67945 0.3048)
			(stroke
				(width 0.1)
				(type default)
			)
			(layer "F.Fab")
		)
		(fp_line
			(start 0.120396 0.2794)
			(end -0.12065 0.2794)
			(stroke
				(width 0.1)
				(type default)
			)
			(layer "F.Fab")
		)
		(fp_line
			(start 0.120396 0.3048)
			(end 0.120396 0.2794)
			(stroke
				(width 0.1)
				(type default)
			)
			(layer "F.Fab")
		)
		(fp_line
			(start 0.12065 -0.3048)
			(end 0.67945 -0.3048)
			(stroke
				(width 0.1)
				(type default)
			)
			(layer "F.Fab")
		)
		(fp_line
			(start 0.12065 -0.2794)
			(end 0.12065 -0.3048)
			(stroke
				(width 0.1)
				(type default)
			)
			(layer "F.Fab")
		)
		(fp_line
			(start 0.67945 -0.3048)
			(end 0.67945 0.3048)
			(stroke
				(width 0.1)
				(type default)
			)
			(layer "F.Fab")
		)
		(fp_line
			(start 0.67945 0.3048)
			(end 0.120396 0.3048)
			(stroke
				(width 0.1)
				(type default)
			)
			(layer "F.Fab")
		)
		(pad "1" smd circle
			(at -0.40005 0)
			(size 0 0)
			(layers "F.Cu" "F.Mask" "F.Paste")
			(net "P3V3_AUX")
		)
		(pad "2" smd circle
			(at 0.40005 0)
			(size 0 0)
			(layers "F.Cu" "F.Mask" "F.Paste")
			(net "JTAG_DBP_PRESENT_R_N")
		)
	)
	(footprint ""
		(layer "F.Cu")
		(at 307.14188 -48.097948)
		(property "Reference" "R7"
			(at 0 0 0)
			(layer "F.SilkS")
			(hide yes)
			(effects
				(font
					(size 1.27 1.27)
				)
			)
		)
		(property "Value" ""
			(at 0 0 0)
			(layer "F.Fab")
			(effects
				(font
					(size 1.27 1.27)
				)
			)
		)
		(duplicate_pad_numbers_are_jumpers no)
		(fp_line
			(start -0.7874 -0.4064)
			(end 0.7874 -0.4064)
			(stroke
				(width 0.1524)
				(type default)
			)
			(layer "F.SilkS")
		)
		(fp_line
			(start -0.7874 0.4064)
			(end -0.7874 -0.4064)
			(stroke
				(width 0.1524)
				(type default)
			)
			(layer "F.SilkS")
		)
		(fp_line
			(start 0.7874 -0.4064)
			(end 0.7874 0.4064)
			(stroke
				(width 0.1524)
				(type default)
			)
			(layer "F.SilkS")
		)
		(fp_line
			(start 0.7874 0.4064)
			(end -0.7874 0.4064)
			(stroke
				(width 0.1524)
				(type default)
			)
			(layer "F.SilkS")
		)
		(fp_line
			(start -0.67945 -0.305054)
			(end -0.12065 -0.305054)
			(stroke
				(width 0.1)
				(type default)
			)
			(layer "F.Fab")
		)
		(fp_line
			(start -0.67945 0.3048)
			(end -0.67945 -0.305054)
			(stroke
				(width 0.1)
				(type default)
			)
			(layer "F.Fab")
		)
		(fp_line
			(start -0.12065 -0.305054)
			(end -0.12065 -0.2794)
			(stroke
				(width 0.1)
				(type default)
			)
			(layer "F.Fab")
		)
		(fp_line
			(start -0.12065 -0.2794)
			(end 0.12065 -0.2794)
			(stroke
				(width 0.1)
				(type default)
			)
			(layer "F.Fab")
		)
		(fp_line
			(start -0.12065 0.2794)
			(end -0.12065 0.3048)
			(stroke
				(width 0.1)
				(type default)
			)
			(layer "F.Fab")
		)
		(fp_line
			(start -0.12065 0.3048)
			(end -0.67945 0.3048)
			(stroke
				(width 0.1)
				(type default)
			)
			(layer "F.Fab")
		)
		(fp_line
			(start 0.120396 0.2794)
			(end -0.12065 0.2794)
			(stroke
				(width 0.1)
				(type default)
			)
			(layer "F.Fab")
		)
		(fp_line
			(start 0.120396 0.3048)
			(end 0.120396 0.2794)
			(stroke
				(width 0.1)
				(type default)
			)
			(layer "F.Fab")
		)
		(fp_line
			(start 0.12065 -0.3048)
			(end 0.67945 -0.3048)
			(stroke
				(width 0.1)
				(type default)
			)
			(layer "F.Fab")
		)
		(fp_line
			(start 0.12065 -0.2794)
			(end 0.12065 -0.3048)
			(stroke
				(width 0.1)
				(type default)
			)
			(layer "F.Fab")
		)
		(fp_line
			(start 0.67945 -0.3048)
			(end 0.67945 0.3048)
			(stroke
				(width 0.1)
				(type default)
			)
			(layer "F.Fab")
		)
		(fp_line
			(start 0.67945 0.3048)
			(end 0.120396 0.3048)
			(stroke
				(width 0.1)
				(type default)
			)
			(layer "F.Fab")
		)
		(pad "1" smd circle
			(at -0.40005 0)
			(size 0 0)
			(layers "F.Cu" "F.Mask" "F.Paste")
			(net "H_CPU0_PMDOWN_PCH_R")
		)
		(pad "2" smd circle
			(at 0.40005 0)
			(size 0 0)
			(layers "F.Cu" "F.Mask" "F.Paste")
			(net "H_CPU0_PMDOWN_PCH")
		)
	)
	(footprint ""
		(layer "F.Cu")
		(at 63.582804 -47.049944 90)
		(property "Reference" "H75"
			(at 4.323137 -0.070988 358.089)
			(unlocked yes)
			(layer "F.SilkS")
			(effects
				(font
					(size 0.7874 0.5842)
					(thickness 0.1524)
				)
			)
		)
		(property "Value" ""
			(at 0 0 90)
			(layer "F.Fab")
			(effects
				(font
					(size 1.27 1.27)
				)
			)
		)
		(duplicate_pad_numbers_are_jumpers no)
		(pad "" np_thru_hole circle
			(at 0 0 90)
			(size 0 0)
			(drill oval 3.2004 4.8006)
			(layers "*.Cu" "*.Mask")
			(clearance -1.2192)
			(thermal_gap 0.381)
			(padstack
				(mode front_inner_back)
				(layer "Inner"
					(shape oval)
					(size 3.2004 4.8006)
					(clearance 0.381)
				)
				(layer "B.Cu"
					(shape circle)
					(size 0 0)
					(clearance -1.2192)
				)
			)
		)
		(zone
			(layers "F.Cu" "B.Cu" "In1.Cu" "In2.Cu" "In3.Cu" "In4.Cu" "In5.Cu" "In6.Cu"
				"In7.Cu" "In8.Cu" "In9.Cu" "In10.Cu" "In11.Cu" "In12.Cu" "In13.Cu" "In14.Cu"
				"In15.Cu" "In16.Cu"
			)
			(hatch none 0.5)
			(connect_pads
				(clearance 0)
			)
			(min_thickness 0.25)
			(keepout
				(tracks not_allowed)
				(vias allowed)
				(pads allowed)
				(copperpour not_allowed)
				(footprints allowed)
			)
			(placement
				(enabled no)
				(sheetname "")
			)
			(fill
				(thermal_gap 0.5)
				(thermal_bridge_width 0.5)
				(island_removal_mode 0)
			)
			(polygon
				(pts
					(arc
						(start 64.38265 -49.158144)
						(mid 66.49085 -47.049944)
						(end 64.38265 -44.941744)
					)
					(arc
						(start 62.782958 -44.941744)
						(mid 60.674758 -47.049944)
						(end 62.782958 -49.158144)
					)
				)
			)
		)
		(zone
			(layers "F.Cu" "B.Cu" "In1.Cu" "In2.Cu" "In3.Cu" "In4.Cu" "In5.Cu" "In6.Cu"
				"In7.Cu" "In8.Cu" "In9.Cu" "In10.Cu" "In11.Cu" "In12.Cu" "In13.Cu" "In14.Cu"
				"In15.Cu" "In16.Cu"
			)
			(hatch none 0.5)
			(connect_pads
				(clearance 0)
			)
			(min_thickness 0.25)
			(keepout
				(tracks not_allowed)
				(vias allowed)
				(pads allowed)
				(copperpour not_allowed)
				(footprints allowed)
			)
			(placement
				(enabled no)
				(sheetname "")
			)
			(fill
				(thermal_gap 0.5)
				(thermal_bridge_width 0.5)
				(island_removal_mode 0)
			)
			(polygon
				(pts
					(arc
						(start 64.382904 -50.050192)
						(mid 67.383152 -47.050071)
						(end 64.383158 -44.049696)
					)
					(arc
						(start 62.782704 -44.049696)
						(mid 59.782456 -47.049817)
						(end 62.78245 -50.050192)
					)
				)
			)
		)
	)
)
